(kicad_pcb
	(version 20260206)
	(generator "pcbnew")
	(generator_version "10.0")
	(general
		(thickness 1.6)
		(legacy_teardrops no)
	)
	(paper "A4")
	(title_block
		(title "04192023_DAF0TMB3IC0_F0TG_MB_C_brd_V02_OCP.brd")
		(comment 1 "Grand Teton / footprint 3 of 8354 (J21), pads 1-113 of 291")
	)
	(layers
		(0 "F.Cu" signal "TOP")
		(4 "In1.Cu" signal "GND")
		(6 "In2.Cu" signal "IN1")
		(8 "In3.Cu" signal "GND1")
		(10 "In4.Cu" signal "IN2")
		(12 "In5.Cu" signal "GND2")
		(14 "In6.Cu" signal "IN3")
		(16 "In7.Cu" signal "GND3")
		(18 "In8.Cu" signal "VCC")
		(20 "In9.Cu" signal "VCC1")
		(22 "In10.Cu" signal "GND4")
		(24 "In11.Cu" signal "IN4")
		(26 "In12.Cu" signal "GND5")
		(28 "In13.Cu" signal "IN5")
		(30 "In14.Cu" signal "GND6")
		(32 "In15.Cu" signal "IN6")
		(34 "In16.Cu" signal "GND7")
		(2 "B.Cu" signal "BOTTOM")
		(9 "F.Adhes" user "F.Adhesive")
		(11 "B.Adhes" user "B.Adhesive")
		(13 "F.Paste" user "Package Geometry/Pastemask Top")
		(15 "B.Paste" user "Package Geometry/Pastemask Bottom")
		(5 "F.SilkS" user "Ref Des/Silkscreen Top")
		(7 "B.SilkS" user "Ref Des/Silkscreen Bottom")
		(1 "F.Mask" user "Board Geometry/Soldermask Top")
		(3 "B.Mask" user "Board Geometry/Soldermask Bottom")
		(17 "Dwgs.User" user "User.Drawings")
		(19 "Cmts.User" user "User.Comments")
		(21 "Eco1.User" user "User.Eco1")
		(23 "Eco2.User" user "User.Eco2")
		(25 "Edge.Cuts" user "Board Geometry/Outline")
		(27 "Margin" user)
		(31 "F.CrtYd" user "Package Geometry/Place Bound Top")
		(29 "B.CrtYd" user "Package Geometry/Place Bound Bottom")
		(35 "F.Fab" user "Ref Des/Assembly Top")
		(33 "B.Fab" user "Ref Des/Assembly Bottom")
	)
	(footprint ""
		(layer "F.Cu")
		(at 275.142198 -255.560068 180)
		(property "Reference" "J21"
			(at -2.2098 -81.984088 0)
			(unlocked yes)
			(layer "F.SilkS")
			(effects
				(font
					(size 0.7874 0.5842)
					(thickness 0.1524)
				)
			)
		)
		(property "Value" ""
			(at 0 0 180)
			(layer "F.Fab")
			(effects
				(font
					(size 1.27 1.27)
				)
			)
		)
		(duplicate_pad_numbers_are_jumpers no)
		(pad "1" smd rect
			(at -2.050034 -63.324994 90)
			(size 0.519938 1.4986)
			(layers "F.Cu" "F.Mask" "F.Paste")
			(net "P12V_MEM_CPU0")
		)
		(pad "2" smd rect
			(at -2.050034 -62.47511 90)
			(size 0.519938 1.4986)
			(layers "F.Cu" "F.Mask" "F.Paste")
			(net "Net_2305")
		)
		(pad "3" smd rect
			(at -2.050034 -61.624972 90)
			(size 0.519938 1.4986)
			(layers "F.Cu" "F.Mask" "F.Paste")
			(net "P3V3_AUX")
		)
		(pad "4" smd rect
			(at -2.050034 -60.775088 90)
			(size 0.519938 1.4986)
			(layers "F.Cu" "F.Mask" "F.Paste")
			(net "I3C_SPD_DDRE_CPU0_SCL")
		)
		(pad "5" smd rect
			(at -2.050034 -59.92495 90)
			(size 0.519938 1.4986)
			(layers "F.Cu" "F.Mask" "F.Paste")
			(net "I3C_SPD_DDRE_CPU0_SDA")
		)
		(pad "6" smd rect
			(at -2.050034 -59.075066 90)
			(size 0.519938 1.4986)
			(layers "F.Cu" "F.Mask" "F.Paste")
			(net "GND")
		)
		(pad "7" smd rect
			(at -2.050034 -58.224928 90)
			(size 0.519938 1.4986)
			(layers "F.Cu" "F.Mask" "F.Paste")
			(net "M_E_CPU0_SA_DQ<0>")
		)
		(pad "8" smd rect
			(at -2.050034 -57.375044 90)
			(size 0.519938 1.4986)
			(layers "F.Cu" "F.Mask" "F.Paste")
			(net "GND")
		)
		(pad "9" smd rect
			(at -2.050034 -56.524906 90)
			(size 0.519938 1.4986)
			(layers "F.Cu" "F.Mask" "F.Paste")
			(net "M_E_CPU0_SA_DQ<1>")
		)
		(pad "10" smd rect
			(at -2.050034 -55.675022 90)
			(size 0.519938 1.4986)
			(layers "F.Cu" "F.Mask" "F.Paste")
			(net "GND")
		)
		(pad "11" smd rect
			(at -2.050034 -54.824884 90)
			(size 0.519938 1.4986)
			(layers "F.Cu" "F.Mask" "F.Paste")
			(net "M_E_CPU0_SA_DQS_DP<0>")
		)
		(pad "12" smd rect
			(at -2.050034 -53.975 90)
			(size 0.519938 1.4986)
			(layers "F.Cu" "F.Mask" "F.Paste")
			(net "M_E_CPU0_SA_DQS_DN<0>")
		)
		(pad "13" smd rect
			(at -2.050034 -53.125116 90)
			(size 0.519938 1.4986)
			(layers "F.Cu" "F.Mask" "F.Paste")
			(net "GND")
		)
		(pad "14" smd rect
			(at -2.050034 -52.274978 90)
			(size 0.519938 1.4986)
			(layers "F.Cu" "F.Mask" "F.Paste")
			(net "M_E_CPU0_SA_DQ<4>")
		)
		(pad "15" smd rect
			(at -2.050034 -51.425094 90)
			(size 0.519938 1.4986)
			(layers "F.Cu" "F.Mask" "F.Paste")
			(net "GND")
		)
		(pad "16" smd rect
			(at -2.050034 -50.574956 90)
			(size 0.519938 1.4986)
			(layers "F.Cu" "F.Mask" "F.Paste")
			(net "M_E_CPU0_SA_DQ<5>")
		)
		(pad "17" smd rect
			(at -2.050034 -49.725072 90)
			(size 0.519938 1.4986)
			(layers "F.Cu" "F.Mask" "F.Paste")
			(net "GND")
		)
		(pad "18" smd rect
			(at -2.050034 -48.874934 90)
			(size 0.519938 1.4986)
			(layers "F.Cu" "F.Mask" "F.Paste")
			(net "M_E_CPU0_SA_DQ<8>")
		)
		(pad "19" smd rect
			(at -2.050034 -48.02505 90)
			(size 0.519938 1.4986)
			(layers "F.Cu" "F.Mask" "F.Paste")
			(net "GND")
		)
		(pad "20" smd rect
			(at -2.050034 -47.174912 90)
			(size 0.519938 1.4986)
			(layers "F.Cu" "F.Mask" "F.Paste")
			(net "M_E_CPU0_SA_DQ<9>")
		)
		(pad "21" smd rect
			(at -2.050034 -46.325028 90)
			(size 0.519938 1.4986)
			(layers "F.Cu" "F.Mask" "F.Paste")
			(net "GND")
		)
		(pad "22" smd rect
			(at -2.050034 -45.47489 90)
			(size 0.519938 1.4986)
			(layers "F.Cu" "F.Mask" "F.Paste")
			(net "M_E_CPU0_SA_DQS_DP<1>")
		)
		(pad "23" smd rect
			(at -2.050034 -44.625006 90)
			(size 0.519938 1.4986)
			(layers "F.Cu" "F.Mask" "F.Paste")
			(net "M_E_CPU0_SA_DQS_DN<1>")
		)
		(pad "24" smd rect
			(at -2.050034 -43.775122 90)
			(size 0.519938 1.4986)
			(layers "F.Cu" "F.Mask" "F.Paste")
			(net "GND")
		)
		(pad "25" smd rect
			(at -2.050034 -42.924984 90)
			(size 0.519938 1.4986)
			(layers "F.Cu" "F.Mask" "F.Paste")
			(net "M_E_CPU0_SA_DQ<12>")
		)
		(pad "26" smd rect
			(at -2.050034 -42.0751 90)
			(size 0.519938 1.4986)
			(layers "F.Cu" "F.Mask" "F.Paste")
			(net "GND")
		)
		(pad "27" smd rect
			(at -2.050034 -41.224962 90)
			(size 0.519938 1.4986)
			(layers "F.Cu" "F.Mask" "F.Paste")
			(net "M_E_CPU0_SA_DQ<13>")
		)
		(pad "28" smd rect
			(at -2.050034 -40.375078 90)
			(size 0.519938 1.4986)
			(layers "F.Cu" "F.Mask" "F.Paste")
			(net "GND")
		)
		(pad "29" smd rect
			(at -2.050034 -39.52494 90)
			(size 0.519938 1.4986)
			(layers "F.Cu" "F.Mask" "F.Paste")
			(net "M_E_CPU0_SA_DQ<16>")
		)
		(pad "30" smd rect
			(at -2.050034 -38.675056 90)
			(size 0.519938 1.4986)
			(layers "F.Cu" "F.Mask" "F.Paste")
			(net "GND")
		)
		(pad "31" smd rect
			(at -2.050034 -37.824918 90)
			(size 0.519938 1.4986)
			(layers "F.Cu" "F.Mask" "F.Paste")
			(net "M_E_CPU0_SA_DQ<17>")
		)
		(pad "32" smd rect
			(at -2.050034 -36.975034 90)
			(size 0.519938 1.4986)
			(layers "F.Cu" "F.Mask" "F.Paste")
			(net "GND")
		)
		(pad "33" smd rect
			(at -2.050034 -36.124896 90)
			(size 0.519938 1.4986)
			(layers "F.Cu" "F.Mask" "F.Paste")
			(net "M_E_CPU0_SA_DQS_DP<2>")
		)
		(pad "34" smd rect
			(at -2.050034 -35.275012 90)
			(size 0.519938 1.4986)
			(layers "F.Cu" "F.Mask" "F.Paste")
			(net "M_E_CPU0_SA_DQS_DN<2>")
		)
		(pad "35" smd rect
			(at -2.050034 -34.425128 90)
			(size 0.519938 1.4986)
			(layers "F.Cu" "F.Mask" "F.Paste")
			(net "GND")
		)
		(pad "36" smd rect
			(at -2.050034 -33.57499 90)
			(size 0.519938 1.4986)
			(layers "F.Cu" "F.Mask" "F.Paste")
			(net "M_E_CPU0_SA_DQ<20>")
		)
		(pad "37" smd rect
			(at -2.050034 -32.725106 90)
			(size 0.519938 1.4986)
			(layers "F.Cu" "F.Mask" "F.Paste")
			(net "GND")
		)
		(pad "38" smd rect
			(at -2.050034 -31.874968 90)
			(size 0.519938 1.4986)
			(layers "F.Cu" "F.Mask" "F.Paste")
			(net "M_E_CPU0_SA_DQ<21>")
		)
		(pad "39" smd rect
			(at -2.050034 -31.025084 90)
			(size 0.519938 1.4986)
			(layers "F.Cu" "F.Mask" "F.Paste")
			(net "GND")
		)
		(pad "40" smd rect
			(at -2.050034 -30.174946 90)
			(size 0.519938 1.4986)
			(layers "F.Cu" "F.Mask" "F.Paste")
			(net "M_E_CPU0_SA_DQ<24>")
		)
		(pad "41" smd rect
			(at -2.050034 -29.325062 90)
			(size 0.519938 1.4986)
			(layers "F.Cu" "F.Mask" "F.Paste")
			(net "GND")
		)
		(pad "42" smd rect
			(at -2.050034 -28.474924 90)
			(size 0.519938 1.4986)
			(layers "F.Cu" "F.Mask" "F.Paste")
			(net "M_E_CPU0_SA_DQ<25>")
		)
		(pad "43" smd rect
			(at -2.050034 -27.62504 90)
			(size 0.519938 1.4986)
			(layers "F.Cu" "F.Mask" "F.Paste")
			(net "GND")
		)
		(pad "44" smd rect
			(at -2.050034 -26.774902 90)
			(size 0.519938 1.4986)
			(layers "F.Cu" "F.Mask" "F.Paste")
			(net "M_E_CPU0_SA_DQS_DP<3>")
		)
		(pad "45" smd rect
			(at -2.050034 -25.925018 90)
			(size 0.519938 1.4986)
			(layers "F.Cu" "F.Mask" "F.Paste")
			(net "M_E_CPU0_SA_DQS_DN<3>")
		)
		(pad "46" smd rect
			(at -2.050034 -25.07488 90)
			(size 0.519938 1.4986)
			(layers "F.Cu" "F.Mask" "F.Paste")
			(net "GND")
		)
		(pad "47" smd rect
			(at -2.050034 -24.224996 90)
			(size 0.519938 1.4986)
			(layers "F.Cu" "F.Mask" "F.Paste")
			(net "M_E_CPU0_SA_DQ<28>")
		)
		(pad "48" smd rect
			(at -2.050034 -23.375112 90)
			(size 0.519938 1.4986)
			(layers "F.Cu" "F.Mask" "F.Paste")
			(net "GND")
		)
		(pad "49" smd rect
			(at -2.050034 -22.524974 90)
			(size 0.519938 1.4986)
			(layers "F.Cu" "F.Mask" "F.Paste")
			(net "M_E_CPU0_SA_DQ<29>")
		)
		(pad "50" smd rect
			(at -2.050034 -21.67509 90)
			(size 0.519938 1.4986)
			(layers "F.Cu" "F.Mask" "F.Paste")
			(net "GND")
		)
		(pad "51" smd rect
			(at -2.050034 -20.824952 90)
			(size 0.519938 1.4986)
			(layers "F.Cu" "F.Mask" "F.Paste")
			(net "M_E_CPU0_SA_CB<0>")
		)
		(pad "52" smd rect
			(at -2.050034 -19.975068 90)
			(size 0.519938 1.4986)
			(layers "F.Cu" "F.Mask" "F.Paste")
			(net "GND")
		)
		(pad "53" smd rect
			(at -2.050034 -19.12493 90)
			(size 0.519938 1.4986)
			(layers "F.Cu" "F.Mask" "F.Paste")
			(net "M_E_CPU0_SA_CB<1>")
		)
		(pad "54" smd rect
			(at -2.050034 -18.275046 90)
			(size 0.519938 1.4986)
			(layers "F.Cu" "F.Mask" "F.Paste")
			(net "GND")
		)
		(pad "55" smd rect
			(at -2.050034 -17.424908 90)
			(size 0.519938 1.4986)
			(layers "F.Cu" "F.Mask" "F.Paste")
			(net "M_E_CPU0_SA_DQS_DP<4>")
		)
		(pad "56" smd rect
			(at -2.050034 -16.575024 90)
			(size 0.519938 1.4986)
			(layers "F.Cu" "F.Mask" "F.Paste")
			(net "M_E_CPU0_SA_DQS_DN<4>")
		)
		(pad "57" smd rect
			(at -2.050034 -15.724886 90)
			(size 0.519938 1.4986)
			(layers "F.Cu" "F.Mask" "F.Paste")
			(net "GND")
		)
		(pad "58" smd rect
			(at -2.050034 -14.875002 90)
			(size 0.519938 1.4986)
			(layers "F.Cu" "F.Mask" "F.Paste")
			(net "M_E_CPU0_SA_CB<4>")
		)
		(pad "59" smd rect
			(at -2.050034 -14.025118 90)
			(size 0.519938 1.4986)
			(layers "F.Cu" "F.Mask" "F.Paste")
			(net "GND")
		)
		(pad "60" smd rect
			(at -2.050034 -13.17498 90)
			(size 0.519938 1.4986)
			(layers "F.Cu" "F.Mask" "F.Paste")
			(net "M_E_CPU0_SA_CB<5>")
		)
		(pad "61" smd rect
			(at -2.050034 -12.325096 90)
			(size 0.519938 1.4986)
			(layers "F.Cu" "F.Mask" "F.Paste")
			(net "GND")
		)
		(pad "62" smd rect
			(at -2.050034 -11.474958 90)
			(size 0.519938 1.4986)
			(layers "F.Cu" "F.Mask" "F.Paste")
			(net "M_E_CPU0_ALERT_N")
		)
		(pad "63" smd rect
			(at -2.050034 -10.625074 90)
			(size 0.519938 1.4986)
			(layers "F.Cu" "F.Mask" "F.Paste")
			(net "GND")
		)
		(pad "64" smd rect
			(at -2.050034 -9.774936 90)
			(size 0.519938 1.4986)
			(layers "F.Cu" "F.Mask" "F.Paste")
			(net "M_E_CPU0_SA_CS_N<0>")
		)
		(pad "65" smd rect
			(at -2.050034 -8.925052 90)
			(size 0.519938 1.4986)
			(layers "F.Cu" "F.Mask" "F.Paste")
			(net "GND")
		)
		(pad "66" smd rect
			(at -2.050034 -8.074914 90)
			(size 0.519938 1.4986)
			(layers "F.Cu" "F.Mask" "F.Paste")
			(net "M_E_CPU0_SA_CA<0>")
		)
		(pad "67" smd rect
			(at -2.050034 -7.22503 90)
			(size 0.519938 1.4986)
			(layers "F.Cu" "F.Mask" "F.Paste")
			(net "GND")
		)
		(pad "68" smd rect
			(at -2.050034 -6.374892 90)
			(size 0.519938 1.4986)
			(layers "F.Cu" "F.Mask" "F.Paste")
			(net "M_E_CPU0_SA_CA<2>")
		)
		(pad "69" smd rect
			(at -2.050034 -5.525008 90)
			(size 0.519938 1.4986)
			(layers "F.Cu" "F.Mask" "F.Paste")
			(net "GND")
		)
		(pad "70" smd rect
			(at -2.050034 -4.675124 90)
			(size 0.519938 1.4986)
			(layers "F.Cu" "F.Mask" "F.Paste")
			(net "M_E_CPU0_SA_CA<4>")
		)
		(pad "71" smd rect
			(at -2.050034 -3.824986 90)
			(size 0.519938 1.4986)
			(layers "F.Cu" "F.Mask" "F.Paste")
			(net "GND")
		)
		(pad "72" smd rect
			(at -2.050034 -2.975102 90)
			(size 0.519938 1.4986)
			(layers "F.Cu" "F.Mask" "F.Paste")
			(net "M_E_CPU0_SA_CA<6>")
		)
		(pad "73" smd rect
			(at -2.050034 -2.124964 90)
			(size 0.519938 1.4986)
			(layers "F.Cu" "F.Mask" "F.Paste")
			(net "GND")
		)
		(pad "74" smd rect
			(at -2.050034 -1.27508 90)
			(size 0.519938 1.4986)
			(layers "F.Cu" "F.Mask" "F.Paste")
			(net "M_E_CPU0_SA_PAR")
		)
		(pad "75" smd rect
			(at -2.050034 -0.424942 90)
			(size 0.519938 1.4986)
			(layers "F.Cu" "F.Mask" "F.Paste")
			(net "GND")
		)
		(pad "76" smd rect
			(at -2.050034 5.525008 90)
			(size 0.519938 1.4986)
			(layers "F.Cu" "F.Mask" "F.Paste")
			(net "M_E_CPU0_SB_CA<0>")
		)
		(pad "77" smd rect
			(at -2.050034 6.374892 90)
			(size 0.519938 1.4986)
			(layers "F.Cu" "F.Mask" "F.Paste")
			(net "GND")
		)
		(pad "78" smd rect
			(at -2.050034 7.22503 90)
			(size 0.519938 1.4986)
			(layers "F.Cu" "F.Mask" "F.Paste")
			(net "M_E_CPU0_SB_CA<2>")
		)
		(pad "79" smd rect
			(at -2.050034 8.074914 90)
			(size 0.519938 1.4986)
			(layers "F.Cu" "F.Mask" "F.Paste")
			(net "GND")
		)
		(pad "80" smd rect
			(at -2.050034 8.925052 90)
			(size 0.519938 1.4986)
			(layers "F.Cu" "F.Mask" "F.Paste")
			(net "M_E_CPU0_SB_CA<4>")
		)
		(pad "81" smd rect
			(at -2.050034 9.774936 90)
			(size 0.519938 1.4986)
			(layers "F.Cu" "F.Mask" "F.Paste")
			(net "GND")
		)
		(pad "82" smd rect
			(at -2.050034 10.625074 90)
			(size 0.519938 1.4986)
			(layers "F.Cu" "F.Mask" "F.Paste")
			(net "M_E_CPU0_SB_CA<6>")
		)
		(pad "83" smd rect
			(at -2.050034 11.474958 90)
			(size 0.519938 1.4986)
			(layers "F.Cu" "F.Mask" "F.Paste")
			(net "GND")
		)
		(pad "84" smd rect
			(at -2.050034 12.325096 90)
			(size 0.519938 1.4986)
			(layers "F.Cu" "F.Mask" "F.Paste")
			(net "M_E_CPU0_SB_CS_N<0>")
		)
		(pad "85" smd rect
			(at -2.050034 13.17498 90)
			(size 0.519938 1.4986)
			(layers "F.Cu" "F.Mask" "F.Paste")
			(net "GND")
		)
		(pad "86" smd rect
			(at -2.050034 14.025118 90)
			(size 0.519938 1.4986)
			(layers "F.Cu" "F.Mask" "F.Paste")
			(net "M_E_CPU0_SA_RSP<0>")
		)
		(pad "87" smd rect
			(at -2.050034 14.875002 90)
			(size 0.519938 1.4986)
			(layers "F.Cu" "F.Mask" "F.Paste")
			(net "M_E_CPU0_SB_RSP<0>")
		)
		(pad "88" smd rect
			(at -2.050034 15.724886 90)
			(size 0.519938 1.4986)
			(layers "F.Cu" "F.Mask" "F.Paste")
			(net "GND")
		)
		(pad "89" smd rect
			(at -2.050034 16.575024 90)
			(size 0.519938 1.4986)
			(layers "F.Cu" "F.Mask" "F.Paste")
			(net "M_E_CPU0_SB_CB<4>")
		)
		(pad "90" smd rect
			(at -2.050034 17.424908 90)
			(size 0.519938 1.4986)
			(layers "F.Cu" "F.Mask" "F.Paste")
			(net "GND")
		)
		(pad "91" smd rect
			(at -2.050034 18.275046 90)
			(size 0.519938 1.4986)
			(layers "F.Cu" "F.Mask" "F.Paste")
			(net "M_E_CPU0_SB_CB<5>")
		)
		(pad "92" smd rect
			(at -2.050034 19.12493 90)
			(size 0.519938 1.4986)
			(layers "F.Cu" "F.Mask" "F.Paste")
			(net "GND")
		)
		(pad "93" smd rect
			(at -2.050034 19.975068 90)
			(size 0.519938 1.4986)
			(layers "F.Cu" "F.Mask" "F.Paste")
			(net "M_E_CPU0_SB_DQS_DP<9>")
		)
		(pad "94" smd rect
			(at -2.050034 20.824952 90)
			(size 0.519938 1.4986)
			(layers "F.Cu" "F.Mask" "F.Paste")
			(net "M_E_CPU0_SB_DQS_DN<9>")
		)
		(pad "95" smd rect
			(at -2.050034 21.67509 90)
			(size 0.519938 1.4986)
			(layers "F.Cu" "F.Mask" "F.Paste")
			(net "GND")
		)
		(pad "96" smd rect
			(at -2.050034 22.524974 90)
			(size 0.519938 1.4986)
			(layers "F.Cu" "F.Mask" "F.Paste")
			(net "M_E_CPU0_SB_CB<0>")
		)
		(pad "97" smd rect
			(at -2.050034 23.375112 90)
			(size 0.519938 1.4986)
			(layers "F.Cu" "F.Mask" "F.Paste")
			(net "GND")
		)
		(pad "98" smd rect
			(at -2.050034 24.224996 90)
			(size 0.519938 1.4986)
			(layers "F.Cu" "F.Mask" "F.Paste")
			(net "M_E_CPU0_SB_CB<1>")
		)
		(pad "99" smd rect
			(at -2.050034 25.07488 90)
			(size 0.519938 1.4986)
			(layers "F.Cu" "F.Mask" "F.Paste")
			(net "GND")
		)
		(pad "100" smd rect
			(at -2.050034 25.925018 90)
			(size 0.519938 1.4986)
			(layers "F.Cu" "F.Mask" "F.Paste")
			(net "M_E_CPU0_SB_DQ<0>")
		)
		(pad "101" smd rect
			(at -2.050034 26.774902 90)
			(size 0.519938 1.4986)
			(layers "F.Cu" "F.Mask" "F.Paste")
			(net "GND")
		)
		(pad "102" smd rect
			(at -2.050034 27.62504 90)
			(size 0.519938 1.4986)
			(layers "F.Cu" "F.Mask" "F.Paste")
			(net "M_E_CPU0_SB_DQ<1>")
		)
		(pad "103" smd rect
			(at -2.050034 28.474924 90)
			(size 0.519938 1.4986)
			(layers "F.Cu" "F.Mask" "F.Paste")
			(net "GND")
		)
		(pad "104" smd rect
			(at -2.050034 29.325062 90)
			(size 0.519938 1.4986)
			(layers "F.Cu" "F.Mask" "F.Paste")
			(net "M_E_CPU0_SB_DQS_DP<0>")
		)
		(pad "105" smd rect
			(at -2.050034 30.174946 90)
			(size 0.519938 1.4986)
			(layers "F.Cu" "F.Mask" "F.Paste")
			(net "M_E_CPU0_SB_DQS_DN<0>")
		)
		(pad "106" smd rect
			(at -2.050034 31.025084 90)
			(size 0.519938 1.4986)
			(layers "F.Cu" "F.Mask" "F.Paste")
			(net "GND")
		)
		(pad "107" smd rect
			(at -2.050034 31.874968 90)
			(size 0.519938 1.4986)
			(layers "F.Cu" "F.Mask" "F.Paste")
			(net "M_E_CPU0_SB_DQ<4>")
		)
		(pad "108" smd rect
			(at -2.050034 32.725106 90)
			(size 0.519938 1.4986)
			(layers "F.Cu" "F.Mask" "F.Paste")
			(net "GND")
		)
		(pad "109" smd rect
			(at -2.050034 33.57499 90)
			(size 0.519938 1.4986)
			(layers "F.Cu" "F.Mask" "F.Paste")
			(net "M_E_CPU0_SB_DQ<5>")
		)
		(pad "110" smd rect
			(at -2.050034 34.425128 90)
			(size 0.519938 1.4986)
			(layers "F.Cu" "F.Mask" "F.Paste")
			(net "GND")
		)
		(pad "111" smd rect
			(at -2.050034 35.275012 90)
			(size 0.519938 1.4986)
			(layers "F.Cu" "F.Mask" "F.Paste")
			(net "M_E_CPU0_SB_DQ<8>")
		)
		(pad "112" smd rect
			(at -2.050034 36.124896 90)
			(size 0.519938 1.4986)
			(layers "F.Cu" "F.Mask" "F.Paste")
			(net "GND")
		)
		(pad "113" smd rect
			(at -2.050034 36.975034 90)
			(size 0.519938 1.4986)
			(layers "F.Cu" "F.Mask" "F.Paste")
			(net "M_E_CPU0_SB_DQ<9>")
		)
	)
)
